(kicad_pcb
	(version 20221018)
	(generator pcbnew)
	(general
    (thickness 1.6)
  )
	(paper "A4")
	(title_block
    (title "NUC Computer Cluster Power Breakout HW")
    (date "2023-10-18")
    (rev "1.4.3")
    (company "Antmicro Ltd.")
		(comment 9 "footprints 220-225 of 234")
	)
	(layers
    (0 "F.Cu" mixed)
    (1 "In1.Cu" power)
    (2 "In2.Cu" mixed)
    (31 "B.Cu" power)
    (32 "B.Adhes" user "B.Adhesive")
    (33 "F.Adhes" user "F.Adhesive")
    (34 "B.Paste" user)
    (35 "F.Paste" user)
    (36 "B.SilkS" user "B.Silkscreen")
    (37 "F.SilkS" user "F.Silkscreen")
    (38 "B.Mask" user)
    (39 "F.Mask" user)
    (40 "Dwgs.User" user "User.Drawings")
    (41 "Cmts.User" user "User.Comments")
    (42 "Eco1.User" user "User.Eco1")
    (43 "Eco2.User" user "User.Eco2")
    (44 "Edge.Cuts" user)
    (45 "Margin" user)
    (46 "B.CrtYd" user "B.Courtyard")
    (47 "F.CrtYd" user "F.Courtyard")
    (48 "B.Fab" user)
    (49 "F.Fab" user)
  )
	(footprint "antmicro-footprints:TPD2E009DRTR" (layer "F.Cu")
    (at 181.55 95.25 180)
    (property "Author" "Antmicro")
    (property "License" "Apache-2.0")
    (property "MPN" "PESD5V0S2BQA")
    (property "Manufacturer" "Nexperia")
    (property "Sheetfile" "d1600e-psu-breakout-board.kicad_sch")
    (property "Sheetname" "")
    (property "ki_description" "TVS diode array, 30 kV, SOT-1215, 5V, 45 pF")
    (property "ki_keywords" "SMT, DIODE, SEMICONDUCTOR, TVS, ESD")
    (attr smd)
    (fp_text reference "D13" (at 0.1 -1.3064) (layer "F.SilkS")
        (effects (font (size 0.7 0.7) (thickness 0.15)))
    )
    (fp_text value "PESD5V0S2BQA" (at 5.6088 1.3064) (layer "F.Fab") hide
        (effects (font (size 0.64 0.64) (thickness 0.015)))
    )
    (fp_text user "${REFERENCE}" (at -0.949 4.506 180) (layer "F.Fab") hide
        (effects (font (size 0.7 0.7) (thickness 0.15)) (justify left bottom))
    )
    (fp_text user "License: Apache-2.0" (at -0.949 5.706 180) (layer "F.Fab") hide
        (effects (font (size 0.7 0.7) (thickness 0.15)) (justify left bottom))
    )
    (fp_text user "Author: Antmicro" (at -0.949 3.306 180) (layer "F.Fab") hide
        (effects (font (size 0.7 0.7) (thickness 0.15)) (justify left bottom))
    )
    (fp_line (start 0.03 -0.499) (end 0.4 -0.499)
      (stroke (width 0.15) (type solid)) (layer "F.SilkS"))
    (fp_line (start 0.03 0.499) (end 0.4 0.499)
      (stroke (width 0.15) (type solid)) (layer "F.SilkS"))
    (fp_line (start 0.4 -0.419) (end 0.4 -0.499)
      (stroke (width 0.15) (type solid)) (layer "F.SilkS"))
    (fp_line (start 0.4 0.42) (end 0.4 0.499)
      (stroke (width 0.15) (type solid)) (layer "F.SilkS"))
    (fp_circle (center -0.5 -0.6) (end -0.45 -0.6)
      (stroke (width 0.15) (type solid)) (fill solid) (layer "F.SilkS"))
    (fp_rect (start -0.8 -0.59) (end 0.8 0.59)
      (stroke (width 0.05) (type solid)) (fill none) (layer "F.CrtYd"))
    (fp_line (start -0.4 -0.499) (end 0.4 -0.499)
      (stroke (width 0.15) (type solid)) (layer "F.Fab"))
    (fp_line (start -0.4 0.499) (end -0.4 -0.499)
      (stroke (width 0.15) (type solid)) (layer "F.Fab"))
    (fp_line (start 0.4 -0.499) (end 0.4 0.499)
      (stroke (width 0.15) (type solid)) (layer "F.Fab"))
    (fp_line (start 0.4 0.499) (end -0.4 0.499)
      (stroke (width 0.15) (type solid)) (layer "F.Fab"))
    (pad "1" smd rect (at -0.52 -0.349 180) (size 0.46 0.2) (layers "F.Cu" "F.Paste" "F.Mask")
      (net 17 "SCL") (pinfunction "IO1") (pintype "passive"))
    (pad "2" smd rect (at -0.52 0.348 180) (size 0.46 0.2) (layers "F.Cu" "F.Paste" "F.Mask")
      (net 18 "SDA") (pinfunction "IO2") (pintype "passive"))
    (pad "3" smd rect (at 0.52 0 180) (size 0.46 0.2) (layers "F.Cu" "F.Paste" "F.Mask")
      (net 4 "GND") (pinfunction "GND") (pintype "passive"))
  )
	(footprint "antmicro-footprints:TP_SMD_1mm" (layer "F.Cu")
    (at 162.8 111.7)
    (property "Author" "Antmicro")
    (property "License" "Apache-2.0")
    (property "MPN" "")
    (property "Manufacturer" "")
    (property "Sheetfile" "ftdi-module.kicad_sch")
    (property "Sheetname" "FTDI")
    (property "exclude_from_bom" "")
    (property "ki_description" "Test point 1mm SMD")
    (property "ki_keywords" "TESTPOINT")
    (attr exclude_from_pos_files exclude_from_bom)
    (fp_text reference "WP1" (at -2.95 0.45) (layer "F.SilkS")
        (effects (font (size 0.7 0.7) (thickness 0.15)) (justify left bottom))
    )
    (fp_text value "TP_1mm_SMD" (at 0 1.4) (layer "F.Fab")
        (effects (font (size 0.7 0.7) (thickness 0.15)) (justify left bottom))
    )
    (fp_text user "Author: Antmicro" (at -0.5 4) (layer "F.Fab") hide
        (effects (font (size 0.7 0.7) (thickness 0.15)) (justify left bottom))
    )
    (fp_text user "${REFERENCE}" (at -0.5 2.8) (layer "F.Fab") hide
        (effects (font (size 0.7 0.7) (thickness 0.15)) (justify left bottom))
    )
    (fp_text user "License: Apache-2.0" (at -0.5 5.2) (layer "F.Fab") hide
        (effects (font (size 0.7 0.7) (thickness 0.15)) (justify left bottom))
    )
    (fp_circle (center 0 0) (end 0.6 0)
      (stroke (width 0.05) (type default)) (fill none) (layer "F.CrtYd"))
    (pad "1" smd circle (at 0 0) (size 1 1) (layers "F.Cu" "F.Mask")
      (net 33 "/FTDI/WP") (pinfunction "1") (pintype "passive"))
  )
	(footprint "antmicro-footprints:Conn_Molex_KK_1x4_22-27-2041" (layer "F.Cu")
    (at 117.34 53.85)
    (property "Author" "Antmicro")
    (property "License" "Apache-2.0")
    (property "MPN" "22-27-2041")
    (property "Manufacturer" "Molex")
    (property "Sheetfile" "d1600e-psu-breakout-board.kicad_sch")
    (property "Sheetname" "")
    (property "ki_description" "Rectangular connector (header, female pins)")
    (property "ki_keywords" "VERTICAL, THT, HEADER, CONNECTOR, MALE")
    (attr through_hole)
    (fp_text reference "J11" (at 3.885 4.15) (layer "F.SilkS")
        (effects (font (size 0.7 0.7) (thickness 0.15)) (justify left bottom))
    )
    (fp_text value "Molex_KK_1x4_22-27-2041" (at -0.8 4.6 180) (layer "F.Fab")
        (effects (font (size 0.7 0.7) (thickness 0.15)) (justify left bottom))
    )
    (fp_text user "Author: Antmicro" (at -2.12 6.75) (layer "F.Fab") hide
        (effects (font (size 0.7 0.7) (thickness 0.15)) (justify left bottom))
    )
    (fp_text user "${REFERENCE}" (at -2.12 9.15) (layer "F.Fab") hide
        (effects (font (size 0.7 0.7) (thickness 0.15)) (justify left bottom))
    )
    (fp_text user "License: Apache-2.0" (at -2.12 7.95) (layer "F.Fab") hide
        (effects (font (size 0.7 0.7) (thickness 0.15)) (justify left bottom))
    )
    (fp_line (start -1.39 -3.03) (end -1.39 2.99)
      (stroke (width 0.15) (type solid)) (layer "F.SilkS"))
    (fp_line (start -1.39 2.99) (end 8.99 2.99)
      (stroke (width 0.15) (type solid)) (layer "F.SilkS"))
    (fp_line (start -0.81 -3.03) (end -0.81 -2.43)
      (stroke (width 0.15) (type solid)) (layer "F.SilkS"))
    (fp_line (start -0.81 -2.43) (end 0.79 -2.43)
      (stroke (width 0.15) (type solid)) (layer "F.SilkS"))
    (fp_line (start -0.01 1.99) (end 0.24 1.46)
      (stroke (width 0.15) (type solid)) (layer "F.SilkS"))
    (fp_line (start -0.01 1.99) (end 7.61 1.99)
      (stroke (width 0.15) (type solid)) (layer "F.SilkS"))
    (fp_line (start -0.01 2.99) (end -0.01 1.99)
      (stroke (width 0.15) (type solid)) (layer "F.SilkS"))
    (fp_line (start 0.24 1.46) (end 7.36 1.46)
      (stroke (width 0.15) (type solid)) (layer "F.SilkS"))
    (fp_line (start 0.24 2.99) (end 0.24 1.99)
      (stroke (width 0.15) (type solid)) (layer "F.SilkS"))
    (fp_line (start 0.79 -2.43) (end 0.79 -3.03)
      (stroke (width 0.15) (type solid)) (layer "F.SilkS"))
    (fp_line (start 1.73 -3.03) (end 1.73 -2.43)
      (stroke (width 0.15) (type solid)) (layer "F.SilkS"))
    (fp_line (start 1.73 -2.43) (end 3.33 -2.43)
      (stroke (width 0.15) (type solid)) (layer "F.SilkS"))
    (fp_line (start 3.33 -2.43) (end 3.33 -3.03)
      (stroke (width 0.15) (type solid)) (layer "F.SilkS"))
    (fp_line (start 4.27 -3.03) (end 4.27 -2.43)
      (stroke (width 0.15) (type solid)) (layer "F.SilkS"))
    (fp_line (start 4.27 -2.43) (end 5.87 -2.43)
      (stroke (width 0.15) (type solid)) (layer "F.SilkS"))
    (fp_line (start 5.87 -2.43) (end 5.87 -3.03)
      (stroke (width 0.15) (type solid)) (layer "F.SilkS"))
    (fp_line (start 6.81 -3.03) (end 6.81 -2.43)
      (stroke (width 0.15) (type solid)) (layer "F.SilkS"))
    (fp_line (start 6.81 -2.43) (end 8.41 -2.43)
      (stroke (width 0.15) (type solid)) (layer "F.SilkS"))
    (fp_line (start 7.36 1.46) (end 7.61 1.99)
      (stroke (width 0.15) (type solid)) (layer "F.SilkS"))
    (fp_line (start 7.36 2.99) (end 7.36 1.99)
      (stroke (width 0.15) (type solid)) (layer "F.SilkS"))
    (fp_line (start 7.61 1.99) (end 7.61 2.99)
      (stroke (width 0.15) (type solid)) (layer "F.SilkS"))
    (fp_line (start 8.41 -2.43) (end 8.41 -3.03)
      (stroke (width 0.15) (type solid)) (layer "F.SilkS"))
    (fp_line (start 8.99 -3.03) (end -1.39 -3.03)
      (stroke (width 0.15) (type solid)) (layer "F.SilkS"))
    (fp_line (start 8.99 2.99) (end 8.99 -3.03)
      (stroke (width 0.15) (type solid)) (layer "F.SilkS"))
    (fp_line (start -1.79 -3.38) (end -1.79 3.42)
      (stroke (width 0.05) (type solid)) (layer "F.CrtYd"))
    (fp_line (start -1.79 3.42) (end 9.37 3.42)
      (stroke (width 0.05) (type solid)) (layer "F.CrtYd"))
    (fp_line (start 9.37 -3.38) (end -1.79 -3.38)
      (stroke (width 0.05) (type solid)) (layer "F.CrtYd"))
    (fp_line (start 9.37 3.42) (end 9.37 -3.38)
      (stroke (width 0.05) (type solid)) (layer "F.CrtYd"))
    (fp_line (start -1.29 -2.88) (end -1.29 2.92)
      (stroke (width 0.15) (type solid)) (layer "F.Fab"))
    (fp_line (start -1.29 2.92) (end 8.87 2.92)
      (stroke (width 0.15) (type solid)) (layer "F.Fab"))
    (fp_line (start 8.163 0) (end 8.87 -0.5)
      (stroke (width 0.15) (type solid)) (layer "F.Fab"))
    (fp_line (start 8.87 -2.88) (end -1.29 -2.88)
      (stroke (width 0.15) (type solid)) (layer "F.Fab"))
    (fp_line (start 8.87 0.5) (end 8.163 0)
      (stroke (width 0.15) (type solid)) (layer "F.Fab"))
    (fp_line (start 8.87 2.92) (end 8.87 -2.88)
      (stroke (width 0.15) (type solid)) (layer "F.Fab"))
    (pad "1" thru_hole roundrect (at 0 0) (size 1.74 2.19) (drill 1.19) (layers "*.Cu" "*.Mask") (roundrect_rratio 0.143678)
      (net 11 "VCC12V0") (pintype "passive"))
    (pad "2" thru_hole oval (at 2.54 0) (size 1.74 2.19) (drill 1.19) (layers "*.Cu" "*.Mask")
      (net 4 "GND") (pintype "passive"))
    (pad "3" thru_hole oval (at 5.08 0) (size 1.74 2.19) (drill 1.19) (layers "*.Cu" "*.Mask")
      (net 4 "GND") (pintype "passive"))
    (pad "4" thru_hole oval (at 7.62 0) (size 1.74 2.19) (drill 1.19) (layers "*.Cu" "*.Mask")
      (net 2 "VCC5V0") (pintype "passive"))
  )
	(footprint "antmicro-footprints:TP_SMD_1mm" (layer "F.Cu")
    (at 189.15 119.55)
    (property "Author" "Antmicro")
    (property "License" "Apache-2.0")
    (property "MPN" "")
    (property "Manufacturer" "")
    (property "Sheetfile" "ftdi-module.kicad_sch")
    (property "Sheetname" "FTDI")
    (property "exclude_from_bom" "")
    (property "ki_description" "Test point 1mm SMD")
    (property "ki_keywords" "TESTPOINT")
    (attr exclude_from_pos_files exclude_from_bom)
    (fp_text reference "TP3" (at -0.75 1.2 90) (layer "F.SilkS")
        (effects (font (size 0.7 0.7) (thickness 0.15)) (justify left bottom))
    )
    (fp_text value "TP_1mm_SMD" (at 0 1.4) (layer "F.Fab")
        (effects (font (size 0.7 0.7) (thickness 0.15)) (justify left bottom))
    )
    (fp_text user "${REFERENCE}" (at -0.5 2.8) (layer "F.Fab") hide
        (effects (font (size 0.7 0.7) (thickness 0.15)) (justify left bottom))
    )
    (fp_text user "Author: Antmicro" (at -0.5 4) (layer "F.Fab") hide
        (effects (font (size 0.7 0.7) (thickness 0.15)) (justify left bottom))
    )
    (fp_text user "License: Apache-2.0" (at -0.5 5.2) (layer "F.Fab") hide
        (effects (font (size 0.7 0.7) (thickness 0.15)) (justify left bottom))
    )
    (fp_circle (center 0 0) (end 0.6 0)
      (stroke (width 0.05) (type default)) (fill none) (layer "F.CrtYd"))
    (pad "1" smd circle (at 0 0) (size 1 1) (layers "F.Cu" "F.Mask")
      (net 118 "Net-(U1-SBU_{2})") (pinfunction "1") (pintype "passive"))
  )
	(footprint "antmicro-footprints:D_SOD-323" (layer "F.Cu")
    (at 168.75 91.55 -90)
    (property "Author" "Antmicro")
    (property "License" "Apache-2.0")
    (property "MPN" "BZT52B15SV-T")
    (property "Manufacturer" "Rectron")
    (property "Sheetfile" "power-switch.kicad_sch")
    (property "Sheetname" "Power switch 4")
    (property "ki_description" "Zener Single Diode, AEC-Q101, 15 V, 500 mW, SOD-323, 2 Pins, 150 °C, Surface Mount")
    (property "ki_keywords" "SMT, DIODE, SEMICONDUCTOR, ZENER")
    (attr smd)
    (fp_text reference "D17" (at 1.1 -1.95 -90) (layer "F.SilkS")
        (effects (font (size 0.7 0.7) (thickness 0.15)) (justify left bottom))
    )
    (fp_text value "BZT52B15SV-T" (at 0 1.841 -90) (layer "F.Fab")
        (effects (font (size 0.7 0.7) (thickness 0.15)) (justify left bottom))
    )
    (fp_text user "Author: Antmicro" (at -1.4 6.241 -90) (layer "F.Fab") hide
        (effects (font (size 0.7 0.7) (thickness 0.15)) (justify left bottom))
    )
    (fp_text user "License: Apache-2.0" (at -1.4 3.841 -90) (layer "F.Fab") hide
        (effects (font (size 0.7 0.7) (thickness 0.15)) (justify left bottom))
    )
    (fp_text user "${REFERENCE}" (at -1.4 5.041 -90) (layer "F.Fab") hide
        (effects (font (size 0.7 0.7) (thickness 0.15)) (justify left bottom))
    )
    (fp_line (start -0.949 -0.749) (end -0.949 -0.499)
      (stroke (width 0.15) (type solid)) (layer "F.SilkS"))
    (fp_line (start -0.949 0.501) (end -0.949 0.751)
      (stroke (width 0.15) (type solid)) (layer "F.SilkS"))
    (fp_line (start -0.6 -0.499) (end -0.6 0.499)
      (stroke (width 0.15) (type solid)) (layer "F.SilkS"))
    (fp_line (start -0.577 -0.749) (end -0.949 -0.749)
      (stroke (width 0.15) (type solid)) (layer "F.SilkS"))
    (fp_line (start -0.577 0.751) (end -0.949 0.751)
      (stroke (width 0.15) (type solid)) (layer "F.SilkS"))
    (fp_line (start 0.625 -0.736) (end 0.949 -0.736)
      (stroke (width 0.15) (type solid)) (layer "F.SilkS"))
    (fp_line (start 0.949 -0.736) (end 0.949 -0.499)
      (stroke (width 0.15) (type solid)) (layer "F.SilkS"))
    (fp_line (start 0.95 0.501) (end 0.95 0.751)
      (stroke (width 0.15) (type solid)) (layer "F.SilkS"))
    (fp_line (start 0.95 0.751) (end 0.649 0.751)
      (stroke (width 0.15) (type solid)) (layer "F.SilkS"))
    (fp_rect (start -1.6 -0.925) (end 1.6 0.925)
      (stroke (width 0.05) (type solid)) (fill none) (layer "F.CrtYd"))
    (fp_line (start -0.902 0.699) (end -0.902 -0.699)
      (stroke (width 0.15) (type solid)) (layer "F.Fab"))
    (fp_line (start -0.902 0.699) (end 0.9 0.699)
      (stroke (width 0.15) (type solid)) (layer "F.Fab"))
    (fp_line (start 0.9 -0.699) (end -0.902 -0.699)
      (stroke (width 0.15) (type solid)) (layer "F.Fab"))
    (fp_line (start 0.9 -0.699) (end 0.9 0.699)
      (stroke (width 0.15) (type solid)) (layer "F.Fab"))
    (pad "1" smd rect (at -1.125 0.001 270) (size 0.8 0.8) (layers "F.Cu" "F.Paste" "F.Mask")
      (net 11 "VCC12V0") (pinfunction "C") (pintype "passive"))
    (pad "2" smd rect (at 1.124 0.001 270) (size 0.8 0.8) (layers "F.Cu" "F.Paste" "F.Mask")
      (net 85 "Net-(D17-A)") (pinfunction "A") (pintype "passive"))
  )
	(footprint "antmicro-footprints:LED_0603_1608Metric_G" (layer "F.Cu")
    (at 94.2 101.6)
    (descr "LED SMD 0603 Green")
    (tags "LED SMD 0603 Green")
    (property "Author" "Antmicro")
    (property "Color" "Green")
    (property "License" "Apache-2.0")
    (property "MPN" "LG L29K-G2J1-24-Z")
    (property "Manufacturer" "OSRAM")
    (property "Sheetfile" "d1600e-psu-breakout-board.kicad_sch")
    (property "Sheetname" "")
    (property "ki_description" "LED, Green, SMD, 0603, 20 mA, 1.7 V, 570 nm")
    (property "ki_keywords" "SMT, DIODE, SEMICONDUCTOR, LED")
    (zone_connect 1)
    (attr smd)
    (fp_text reference "D9" (at -0.7 -0.7) (layer "F.SilkS")
        (effects (font (size 0.7 0.7) (thickness 0.15)) (justify left bottom))
    )
    (fp_text value "LED_G_0603_LG_L29K-G2J1-24-Z" (at -0.001 1.599) (layer "F.Fab")
        (effects (font (size 0.7 0.7) (thickness 0.15)) (justify left bottom))
    )
    (fp_text user "${REFERENCE}" (at -1.4224 5.999) (layer "F.Fab") hide
        (effects (font (size 0.7 0.7) (thickness 0.15)) (justify left bottom))
    )
    (fp_text user "License: Apache-2.0" (at -1.4224 3.599) (layer "F.Fab") hide
        (effects (font (size 0.7 0.7) (thickness 0.15)) (justify left bottom))
    )
    (fp_text user "Author: Antmicro" (at -1.4224 4.799) (layer "F.Fab") hide
        (effects (font (size 0.7 0.7) (thickness 0.15)) (justify left bottom))
    )
    (fp_line (start -1.18 -0.319) (end -1.18 0.321)
      (stroke (width 0.15) (type solid)) (layer "F.SilkS"))
    (fp_line (start -0.094672 0.001008) (end -0.24 0.001008)
      (stroke (width 0.1) (type solid)) (layer "F.SilkS"))
    (fp_line (start -0.094672 0.001008) (end 0.105328 -0.198992)
      (stroke (width 0.1) (type solid)) (layer "F.SilkS"))
    (fp_line (start -0.094672 0.201008) (end -0.094672 -0.198992)
      (stroke (width 0.1) (type solid)) (layer "F.SilkS"))
    (fp_line (start 0.105328 0.001008) (end 0.24 0.001)
      (stroke (width 0.1) (type solid)) (layer "F.SilkS"))
    (fp_line (start 0.105328 0.201008) (end -0.094672 0.001008)
      (stroke (width 0.1) (type solid)) (layer "F.SilkS"))
    (fp_line (start 0.105328 0.201008) (end 0.105328 -0.198992)
      (stroke (width 0.1) (type solid)) (layer "F.SilkS"))
    (fp_line (start 0.22 -0.35) (end -0.22 -0.35)
      (stroke (width 0.15) (type solid)) (layer "F.SilkS"))
    (fp_line (start 0.22 0.35) (end -0.22 0.35)
      (stroke (width 0.15) (type solid)) (layer "F.SilkS"))
    (fp_rect (start 1.25 0.65) (end -1.25 -0.65)
      (stroke (width 0.05) (type solid)) (fill none) (layer "F.CrtYd"))
    (fp_line (start -0.199 -0.202) (end -0.199 0.1)
      (stroke (width 0.15) (type solid)) (layer "F.Fab"))
    (fp_line (start -0.199 0) (end -0.597 0)
      (stroke (width 0.15) (type solid)) (layer "F.Fab"))
    (fp_line (start -0.199 0.2) (end -0.199 0.1)
      (stroke (width 0.15) (type solid)) (layer "F.Fab"))
    (fp_line (start -0.101 0) (end 0.201 0.2)
      (stroke (width 0.15) (type solid)) (layer "F.Fab"))
    (fp_line (start 0.201 -0.202) (end -0.101 0)
      (stroke (width 0.15) (type solid)) (layer "F.Fab"))
    (fp_line (start 0.201 0) (end 0.201 -0.202)
      (stroke (width 0.15) (type solid)) (layer "F.Fab"))
    (fp_line (start 0.201 0.2) (end 0.201 0)
      (stroke (width 0.15) (type solid)) (layer "F.Fab"))
    (fp_line (start 0.599 0) (end 0.201 0)
      (stroke (width 0.15) (type solid)) (layer "F.Fab"))
    (fp_rect (start 0.848 0.4) (end -0.85 -0.402)
      (stroke (width 0.15) (type solid)) (fill none) (layer "F.Fab"))
    (pad "1" smd roundrect (at -0.7 0 180) (size 0.8 1) (layers "F.Cu" "F.Paste" "F.Mask") (roundrect_rratio 0.2)
      (net 4 "GND") (pinfunction "C") (pintype "passive"))
    (pad "2" smd roundrect (at 0.7 0 180) (size 0.8 1) (layers "F.Cu" "F.Paste" "F.Mask") (roundrect_rratio 0.2)
      (net 78 "Net-(D9-A)") (pinfunction "A") (pintype "passive"))
  )
)
